(kicad_pcb
	(version 20260206)
	(generator "pcbnew")
	(generator_version "10.0")
	(general
		(thickness 1.6)
		(legacy_teardrops no)
	)
	(paper "A4")
	(title_block
		(title "01162023_DA0F0TEBIF0_F0T_Expander_BD_F_brd_V02_OCP.brd")
		(comment 1 "Grand Teton / footprints 4123-4127 of 9728")
	)
	(layers
		(0 "F.Cu" signal "TOP")
		(4 "In1.Cu" signal "GND")
		(6 "In2.Cu" signal "VCC")
		(8 "In3.Cu" signal "VCC1")
		(10 "In4.Cu" signal "GND1")
		(12 "In5.Cu" signal "IN1")
		(14 "In6.Cu" signal "GND2")
		(16 "In7.Cu" signal "IN2")
		(18 "In8.Cu" signal "GND3")
		(20 "In9.Cu" signal "IN3")
		(22 "In10.Cu" signal "GND4")
		(24 "In11.Cu" signal "IN4")
		(26 "In12.Cu" signal "GND5")
		(28 "In13.Cu" signal "IN5")
		(30 "In14.Cu" signal "GND6")
		(32 "In15.Cu" signal "IN6")
		(34 "In16.Cu" signal "GND7")
		(2 "B.Cu" signal "BOTTOM")
		(9 "F.Adhes" user "F.Adhesive")
		(11 "B.Adhes" user "B.Adhesive")
		(13 "F.Paste" user "Package Geometry/Pastemask Top")
		(15 "B.Paste" user "Package Geometry/Pastemask Bottom")
		(5 "F.SilkS" user "Ref Des/Silkscreen Top")
		(7 "B.SilkS" user "Ref Des/Silkscreen Bottom")
		(1 "F.Mask" user "Board Geometry/Soldermask Top")
		(3 "B.Mask" user "Board Geometry/Soldermask Bottom")
		(17 "Dwgs.User" user "User.Drawings")
		(19 "Cmts.User" user "User.Comments")
		(21 "Eco1.User" user "User.Eco1")
		(23 "Eco2.User" user "User.Eco2")
		(25 "Edge.Cuts" user "Board Geometry/Outline")
		(27 "Margin" user)
		(31 "F.CrtYd" user "Package Geometry/Place Bound Top")
		(29 "B.CrtYd" user "Package Geometry/Place Bound Bottom")
		(35 "F.Fab" user "Ref Des/Assembly Top")
		(33 "B.Fab" user "Ref Des/Assembly Bottom")
	)
	(footprint ""
		(layer "F.Cu")
		(at 417.92271 -22.867366 90)
		(property "Reference" "C3976"
			(at 0 0 90)
			(layer "F.SilkS")
			(hide yes)
			(effects
				(font
					(size 1.27 1.27)
				)
			)
		)
		(property "Value" ""
			(at 0 0 90)
			(layer "F.Fab")
			(effects
				(font
					(size 1.27 1.27)
				)
			)
		)
		(duplicate_pad_numbers_are_jumpers no)
		(fp_line
			(start 0.7874 -0.4064)
			(end 0.7874 0.4064)
			(stroke
				(width 0.1524)
				(type default)
			)
			(layer "F.SilkS")
		)
		(fp_line
			(start -0.7874 -0.4064)
			(end 0.7874 -0.4064)
			(stroke
				(width 0.1524)
				(type default)
			)
			(layer "F.SilkS")
		)
		(fp_line
			(start 0.7874 0.4064)
			(end -0.7874 0.4064)
			(stroke
				(width 0.1524)
				(type default)
			)
			(layer "F.SilkS")
		)
		(fp_line
			(start -0.7874 0.4064)
			(end -0.7874 -0.4064)
			(stroke
				(width 0.1524)
				(type default)
			)
			(layer "F.SilkS")
		)
		(fp_line
			(start -0.12065 -0.305054)
			(end -0.12065 -0.2794)
			(stroke
				(width 0.1)
				(type default)
			)
			(layer "F.Fab")
		)
		(fp_line
			(start -0.67945 -0.305054)
			(end -0.12065 -0.305054)
			(stroke
				(width 0.1)
				(type default)
			)
			(layer "F.Fab")
		)
		(fp_line
			(start 0.67945 -0.3048)
			(end 0.67945 0.3048)
			(stroke
				(width 0.1)
				(type default)
			)
			(layer "F.Fab")
		)
		(fp_line
			(start 0.12065 -0.3048)
			(end 0.67945 -0.3048)
			(stroke
				(width 0.1)
				(type default)
			)
			(layer "F.Fab")
		)
		(fp_line
			(start 0.12065 -0.2794)
			(end 0.12065 -0.3048)
			(stroke
				(width 0.1)
				(type default)
			)
			(layer "F.Fab")
		)
		(fp_line
			(start -0.12065 -0.2794)
			(end 0.12065 -0.2794)
			(stroke
				(width 0.1)
				(type default)
			)
			(layer "F.Fab")
		)
		(fp_line
			(start 0.120396 0.2794)
			(end -0.12065 0.2794)
			(stroke
				(width 0.1)
				(type default)
			)
			(layer "F.Fab")
		)
		(fp_line
			(start -0.12065 0.2794)
			(end -0.12065 0.3048)
			(stroke
				(width 0.1)
				(type default)
			)
			(layer "F.Fab")
		)
		(fp_line
			(start 0.67945 0.3048)
			(end 0.120396 0.3048)
			(stroke
				(width 0.1)
				(type default)
			)
			(layer "F.Fab")
		)
		(fp_line
			(start 0.120396 0.3048)
			(end 0.120396 0.2794)
			(stroke
				(width 0.1)
				(type default)
			)
			(layer "F.Fab")
		)
		(fp_line
			(start -0.12065 0.3048)
			(end -0.67945 0.3048)
			(stroke
				(width 0.1)
				(type default)
			)
			(layer "F.Fab")
		)
		(fp_line
			(start -0.67945 0.3048)
			(end -0.67945 -0.305054)
			(stroke
				(width 0.1)
				(type default)
			)
			(layer "F.Fab")
		)
		(pad "1" smd circle
			(at -0.40005 0 90)
			(size 0 0)
			(layers "F.Cu" "F.Mask" "F.Paste")
			(net "P12V_SSD14")
		)
		(pad "2" smd circle
			(at 0.40005 0 90)
			(size 0 0)
			(layers "F.Cu" "F.Mask" "F.Paste")
			(net "GND")
		)
	)
	(footprint ""
		(layer "F.Cu")
		(at 369.071144 -145.189956 180)
		(property "Reference" "R756"
			(at 0 0 180)
			(layer "F.SilkS")
			(hide yes)
			(effects
				(font
					(size 1.27 1.27)
				)
			)
		)
		(property "Value" ""
			(at 0 0 180)
			(layer "F.Fab")
			(effects
				(font
					(size 1.27 1.27)
				)
			)
		)
		(duplicate_pad_numbers_are_jumpers no)
		(fp_line
			(start 0.7874 0.4064)
			(end -0.7874 0.4064)
			(stroke
				(width 0.1524)
				(type default)
			)
			(layer "F.SilkS")
		)
		(fp_line
			(start 0.7874 -0.4064)
			(end 0.7874 0.4064)
			(stroke
				(width 0.1524)
				(type default)
			)
			(layer "F.SilkS")
		)
		(fp_line
			(start -0.7874 0.4064)
			(end -0.7874 -0.4064)
			(stroke
				(width 0.1524)
				(type default)
			)
			(layer "F.SilkS")
		)
		(fp_line
			(start -0.7874 -0.4064)
			(end 0.7874 -0.4064)
			(stroke
				(width 0.1524)
				(type default)
			)
			(layer "F.SilkS")
		)
		(fp_line
			(start 0.67945 0.3048)
			(end 0.120396 0.3048)
			(stroke
				(width 0.1)
				(type default)
			)
			(layer "F.Fab")
		)
		(fp_line
			(start 0.67945 -0.3048)
			(end 0.67945 0.3048)
			(stroke
				(width 0.1)
				(type default)
			)
			(layer "F.Fab")
		)
		(fp_line
			(start 0.12065 -0.2794)
			(end 0.12065 -0.3048)
			(stroke
				(width 0.1)
				(type default)
			)
			(layer "F.Fab")
		)
		(fp_line
			(start 0.12065 -0.3048)
			(end 0.67945 -0.3048)
			(stroke
				(width 0.1)
				(type default)
			)
			(layer "F.Fab")
		)
		(fp_line
			(start 0.120396 0.3048)
			(end 0.120396 0.2794)
			(stroke
				(width 0.1)
				(type default)
			)
			(layer "F.Fab")
		)
		(fp_line
			(start 0.120396 0.2794)
			(end -0.12065 0.2794)
			(stroke
				(width 0.1)
				(type default)
			)
			(layer "F.Fab")
		)
		(fp_line
			(start -0.12065 0.3048)
			(end -0.67945 0.3048)
			(stroke
				(width 0.1)
				(type default)
			)
			(layer "F.Fab")
		)
		(fp_line
			(start -0.12065 0.2794)
			(end -0.12065 0.3048)
			(stroke
				(width 0.1)
				(type default)
			)
			(layer "F.Fab")
		)
		(fp_line
			(start -0.12065 -0.2794)
			(end 0.12065 -0.2794)
			(stroke
				(width 0.1)
				(type default)
			)
			(layer "F.Fab")
		)
		(fp_line
			(start -0.12065 -0.305054)
			(end -0.12065 -0.2794)
			(stroke
				(width 0.1)
				(type default)
			)
			(layer "F.Fab")
		)
		(fp_line
			(start -0.67945 0.3048)
			(end -0.67945 -0.305054)
			(stroke
				(width 0.1)
				(type default)
			)
			(layer "F.Fab")
		)
		(fp_line
			(start -0.67945 -0.305054)
			(end -0.12065 -0.305054)
			(stroke
				(width 0.1)
				(type default)
			)
			(layer "F.Fab")
		)
		(pad "1" smd circle
			(at -0.40005 0 180)
			(size 0 0)
			(layers "F.Cu" "F.Mask" "F.Paste")
			(net "P12V_NIC6")
		)
		(pad "2" smd circle
			(at 0.40005 0 180)
			(size 0 0)
			(layers "F.Cu" "F.Mask" "F.Paste")
			(net "P12V_NIC6_VIN_N")
		)
	)
	(footprint ""
		(layer "F.Cu")
		(at 239.754918 -315.821314 180)
		(property "Reference" "PC245"
			(at 0 0 180)
			(layer "F.SilkS")
			(hide yes)
			(effects
				(font
					(size 1.27 1.27)
				)
			)
		)
		(property "Value" ""
			(at 0 0 180)
			(layer "F.Fab")
			(effects
				(font
					(size 1.27 1.27)
				)
			)
		)
		(duplicate_pad_numbers_are_jumpers no)
		(fp_line
			(start 1.524 0.762)
			(end -1.524 0.762)
			(stroke
				(width 0.1524)
				(type default)
			)
			(layer "F.SilkS")
		)
		(fp_line
			(start 1.524 -0.762)
			(end 1.524 0.762)
			(stroke
				(width 0.1524)
				(type default)
			)
			(layer "F.SilkS")
		)
		(fp_line
			(start -1.524 0.762)
			(end -1.524 -0.762)
			(stroke
				(width 0.1524)
				(type default)
			)
			(layer "F.SilkS")
		)
		(fp_line
			(start -1.524 -0.762)
			(end 1.524 -0.762)
			(stroke
				(width 0.1524)
				(type default)
			)
			(layer "F.SilkS")
		)
		(fp_line
			(start 1.1049 0.724916)
			(end 1.1049 -0.724916)
			(stroke
				(width 0.1)
				(type default)
			)
			(layer "F.Fab")
		)
		(fp_line
			(start 1.1049 -0.724916)
			(end -1.1049 -0.724916)
			(stroke
				(width 0.1)
				(type default)
			)
			(layer "F.Fab")
		)
		(fp_line
			(start -1.1049 0.724916)
			(end 1.1049 0.724916)
			(stroke
				(width 0.1)
				(type default)
			)
			(layer "F.Fab")
		)
		(fp_line
			(start -1.1049 -0.724916)
			(end -1.1049 0.724916)
			(stroke
				(width 0.1)
				(type default)
			)
			(layer "F.Fab")
		)
		(pad "1" smd rect
			(at -0.889 0)
			(size 1.016 1.27)
			(layers "F.Cu" "F.Mask" "F.Paste")
			(net "SW_P12V_P1V25_PEX2_FLT")
		)
		(pad "2" smd rect
			(at 0.889 0)
			(size 1.016 1.27)
			(layers "F.Cu" "F.Mask" "F.Paste")
			(net "GND")
		)
	)
	(footprint ""
		(layer "F.Cu")
		(at 171.979844 -142.9512 180)
		(property "Reference" "R111"
			(at 0 0 180)
			(layer "F.SilkS")
			(hide yes)
			(effects
				(font
					(size 1.27 1.27)
				)
			)
		)
		(property "Value" ""
			(at 0 0 180)
			(layer "F.Fab")
			(effects
				(font
					(size 1.27 1.27)
				)
			)
		)
		(duplicate_pad_numbers_are_jumpers no)
		(fp_line
			(start 0.7874 0.4064)
			(end -0.7874 0.4064)
			(stroke
				(width 0.1524)
				(type default)
			)
			(layer "F.SilkS")
		)
		(fp_line
			(start 0.7874 -0.4064)
			(end 0.7874 0.4064)
			(stroke
				(width 0.1524)
				(type default)
			)
			(layer "F.SilkS")
		)
		(fp_line
			(start -0.7874 0.4064)
			(end -0.7874 -0.4064)
			(stroke
				(width 0.1524)
				(type default)
			)
			(layer "F.SilkS")
		)
		(fp_line
			(start -0.7874 -0.4064)
			(end 0.7874 -0.4064)
			(stroke
				(width 0.1524)
				(type default)
			)
			(layer "F.SilkS")
		)
		(fp_line
			(start 0.67945 0.3048)
			(end 0.120396 0.3048)
			(stroke
				(width 0.1)
				(type default)
			)
			(layer "F.Fab")
		)
		(fp_line
			(start 0.67945 -0.3048)
			(end 0.67945 0.3048)
			(stroke
				(width 0.1)
				(type default)
			)
			(layer "F.Fab")
		)
		(fp_line
			(start 0.12065 -0.2794)
			(end 0.12065 -0.3048)
			(stroke
				(width 0.1)
				(type default)
			)
			(layer "F.Fab")
		)
		(fp_line
			(start 0.12065 -0.3048)
			(end 0.67945 -0.3048)
			(stroke
				(width 0.1)
				(type default)
			)
			(layer "F.Fab")
		)
		(fp_line
			(start 0.120396 0.3048)
			(end 0.120396 0.2794)
			(stroke
				(width 0.1)
				(type default)
			)
			(layer "F.Fab")
		)
		(fp_line
			(start 0.120396 0.2794)
			(end -0.12065 0.2794)
			(stroke
				(width 0.1)
				(type default)
			)
			(layer "F.Fab")
		)
		(fp_line
			(start -0.12065 0.3048)
			(end -0.67945 0.3048)
			(stroke
				(width 0.1)
				(type default)
			)
			(layer "F.Fab")
		)
		(fp_line
			(start -0.12065 0.2794)
			(end -0.12065 0.3048)
			(stroke
				(width 0.1)
				(type default)
			)
			(layer "F.Fab")
		)
		(fp_line
			(start -0.12065 -0.2794)
			(end 0.12065 -0.2794)
			(stroke
				(width 0.1)
				(type default)
			)
			(layer "F.Fab")
		)
		(fp_line
			(start -0.12065 -0.305054)
			(end -0.12065 -0.2794)
			(stroke
				(width 0.1)
				(type default)
			)
			(layer "F.Fab")
		)
		(fp_line
			(start -0.67945 0.3048)
			(end -0.67945 -0.305054)
			(stroke
				(width 0.1)
				(type default)
			)
			(layer "F.Fab")
		)
		(fp_line
			(start -0.67945 -0.305054)
			(end -0.12065 -0.305054)
			(stroke
				(width 0.1)
				(type default)
			)
			(layer "F.Fab")
		)
		(pad "1" smd circle
			(at -0.40005 0 180)
			(size 0 0)
			(layers "F.Cu" "F.Mask" "F.Paste")
			(net "P3V3_NIC2")
		)
		(pad "2" smd circle
			(at 0.40005 0 180)
			(size 0 0)
			(layers "F.Cu" "F.Mask" "F.Paste")
			(net "SMB_NIC2_R_SCL")
		)
	)
	(footprint ""
		(layer "F.Cu")
		(at 190.946024 -46.4439 180)
		(property "Reference" "U61"
			(at -0.163576 -2.45237 0)
			(unlocked yes)
			(layer "F.SilkS")
			(effects
				(font
					(size 0.7874 0.5842)
					(thickness 0.1524)
				)
			)
		)
		(property "Value" ""
			(at 0 0 180)
			(layer "F.Fab")
			(effects
				(font
					(size 1.27 1.27)
				)
			)
		)
		(duplicate_pad_numbers_are_jumpers no)
		(fp_line
			(start 1.500124 1.500124)
			(end 1.004062 1.500124)
			(stroke
				(width 0.1524)
				(type default)
			)
			(layer "F.SilkS")
		)
		(fp_line
			(start 1.500124 1.004062)
			(end 1.500124 1.500124)
			(stroke
				(width 0.1524)
				(type default)
			)
			(layer "F.SilkS")
		)
		(fp_line
			(start 1.500124 -1.500124)
			(end 1.500124 -1.004062)
			(stroke
				(width 0.1524)
				(type default)
			)
			(layer "F.SilkS")
		)
		(fp_line
			(start 1.004062 -1.500124)
			(end 1.500124 -1.500124)
			(stroke
				(width 0.1524)
				(type default)
			)
			(layer "F.SilkS")
		)
		(fp_line
			(start -1.004062 1.500124)
			(end -1.500124 1.500124)
			(stroke
				(width 0.1524)
				(type default)
			)
			(layer "F.SilkS")
		)
		(fp_line
			(start -1.500124 1.500124)
			(end -1.500124 1.004062)
			(stroke
				(width 0.1524)
				(type default)
			)
			(layer "F.SilkS")
		)
		(fp_line
			(start -1.500124 -1.004062)
			(end -1.500124 -1.500124)
			(stroke
				(width 0.1524)
				(type default)
			)
			(layer "F.SilkS")
		)
		(fp_line
			(start -1.500124 -1.500124)
			(end -1.004062 -1.500124)
			(stroke
				(width 0.1524)
				(type default)
			)
			(layer "F.SilkS")
		)
		(fp_poly
			(pts
				(xy -1.827022 -2.276602) (xy -2.545334 -1.55829) (xy -1.467612 -1.199134)
			)
			(stroke
				(width 0)
				(type default)
			)
			(fill yes)
			(layer "F.SilkS")
		)
		(fp_line
			(start 1.500124 1.500124)
			(end -1.500124 1.500124)
			(stroke
				(width 0.1)
				(type default)
			)
			(layer "F.Fab")
		)
		(fp_line
			(start 1.500124 -1.500124)
			(end 1.500124 1.500124)
			(stroke
				(width 0.1)
				(type default)
			)
			(layer "F.Fab")
		)
		(fp_line
			(start -1.500124 1.500124)
			(end -1.500124 -1.500124)
			(stroke
				(width 0.1)
				(type default)
			)
			(layer "F.Fab")
		)
		(fp_line
			(start -1.500124 -1.500124)
			(end 1.500124 -1.500124)
			(stroke
				(width 0.1)
				(type default)
			)
			(layer "F.Fab")
		)
		(fp_poly
			(pts
				(xy -2.847848 -1.258062) (xy -2.847848 -0.242062) (xy -1.831848 -0.750062)
			)
			(stroke
				(width 0)
				(type default)
			)
			(fill yes)
			(layer "F.Fab")
		)
		(pad "1" smd rect
			(at -1.400048 -0.750062 90)
			(size 0.2286 0.6096)
			(layers "F.Cu" "F.Mask" "F.Paste")
			(net "SSD6_ADC_A1")
		)
		(pad "2" smd rect
			(at -1.400048 -0.249936 90)
			(size 0.2286 0.6096)
			(layers "F.Cu" "F.Mask" "F.Paste")
			(net "SSD6_ADC_A0")
		)
		(pad "3" smd rect
			(at -1.400048 0.249936 90)
			(size 0.2286 0.6096)
			(layers "F.Cu" "F.Mask" "F.Paste")
			(net "SSD6_ADC_ALERT_N")
		)
		(pad "4" smd rect
			(at -1.400048 0.750062 90)
			(size 0.2286 0.6096)
			(layers "F.Cu" "F.Mask" "F.Paste")
			(net "SMB_SSD6_ADC_SDA")
		)
		(pad "5" smd rect
			(at -0.750062 1.400048 180)
			(size 0.2286 0.6096)
			(layers "F.Cu" "F.Mask" "F.Paste")
			(net "SMB_SSD6_ADC_SCL")
		)
		(pad "6" smd rect
			(at -0.249936 1.400048 180)
			(size 0.2286 0.6096)
			(layers "F.Cu" "F.Mask" "F.Paste")
			(net "Net_8726")
		)
		(pad "7" smd rect
			(at 0.249936 1.400048 180)
			(size 0.2286 0.6096)
			(layers "F.Cu" "F.Mask" "F.Paste")
			(net "Net_8725")
		)
		(pad "8" smd rect
			(at 0.750062 1.400048 180)
			(size 0.2286 0.6096)
			(layers "F.Cu" "F.Mask" "F.Paste")
			(net "Net_8724")
		)
		(pad "9" smd rect
			(at 1.400048 0.750062 90)
			(size 0.2286 0.6096)
			(layers "F.Cu" "F.Mask" "F.Paste")
			(net "P3V3_AUX")
		)
		(pad "10" smd rect
			(at 1.400048 0.249936 90)
			(size 0.2286 0.6096)
			(layers "F.Cu" "F.Mask" "F.Paste")
			(net "GND")
		)
		(pad "11" smd rect
			(at 1.400048 -0.249936 90)
			(size 0.2286 0.6096)
			(layers "F.Cu" "F.Mask" "F.Paste")
			(net "P12V_SSD6_R")
		)
		(pad "12" smd rect
			(at 1.400048 -0.750062 90)
			(size 0.2286 0.6096)
			(layers "F.Cu" "F.Mask" "F.Paste")
			(net "P12V_SSD6_VIN_N")
		)
		(pad "13" smd rect
			(at 0.750062 -1.400048 180)
			(size 0.2286 0.6096)
			(layers "F.Cu" "F.Mask" "F.Paste")
			(net "P12V_SSD6_VIN_P")
		)
		(pad "14" smd rect
			(at 0.249936 -1.400048 180)
			(size 0.2286 0.6096)
			(layers "F.Cu" "F.Mask" "F.Paste")
			(net "Net_8723")
		)
		(pad "15" smd rect
			(at -0.249936 -1.400048 180)
			(size 0.2286 0.6096)
			(layers "F.Cu" "F.Mask" "F.Paste")
			(net "Net_8722")
		)
		(pad "16" smd rect
			(at -0.750062 -1.400048 180)
			(size 0.2286 0.6096)
			(layers "F.Cu" "F.Mask" "F.Paste")
			(net "Net_8721")
		)
		(pad "TH" smd rect
			(at 0 0 180)
			(size 1.7018 1.7018)
			(layers "F.Cu" "F.Mask" "F.Paste")
			(net "GND")
		)
		(zone
			(layer "F.Cu")
			(hatch none 0.5)
			(connect_pads
				(clearance 0)
			)
			(min_thickness 0.25)
			(keepout
				(tracks not_allowed)
				(vias allowed)
				(pads allowed)
				(copperpour not_allowed)
				(footprints allowed)
			)
			(placement
				(enabled no)
				(sheetname "")
			)
			(fill
				(thermal_gap 0.5)
				(thermal_bridge_width 0.5)
				(island_removal_mode 0)
			)
			(polygon
				(pts
					(xy 191.990472 -46.4185) (xy 191.990472 -45.399452) (xy 189.901576 -45.399452) (xy 189.901576 -47.488348)
					(xy 191.990472 -47.488348) (xy 191.990472 -46.4439) (xy 191.847724 -46.4439) (xy 191.847724 -47.3456)
					(xy 190.044324 -47.3456) (xy 190.044324 -45.5422) (xy 191.847724 -45.5422) (xy 191.847724 -46.4185)
				)
			)
		)
	)
)
